(kicad_pcb
	(version 20260206)
	(generator "pcbnew")
	(generator_version "10.0")
	(general
		(thickness 1.6)
		(legacy_teardrops no)
	)
	(paper "A4")
	(title_block
		(title "peb — Lightning_PEB_BRD.brd")
		(comment 1 "Lightning (Wiwynn / Facebook NVMe JBOF) / footprints 1528-1534 of 2563")
	)
	(layers
		(0 "F.Cu" signal "TOP")
		(4 "In1.Cu" signal "L2GND")
		(6 "In2.Cu" signal "L3")
		(8 "In3.Cu" signal "L4VCC")
		(10 "In4.Cu" signal "L5VCC")
		(12 "In5.Cu" signal "L6")
		(14 "In6.Cu" signal "L7GND")
		(2 "B.Cu" signal "BOTTOM")
		(9 "F.Adhes" user "F.Adhesive")
		(11 "B.Adhes" user "B.Adhesive")
		(13 "F.Paste" user "Package Geometry/Pastemask Top")
		(15 "B.Paste" user "Package Geometry/Pastemask Bottom")
		(5 "F.SilkS" user "Ref Des/Silkscreen Top")
		(7 "B.SilkS" user "Ref Des/Silkscreen Bottom")
		(1 "F.Mask" user "Board Geometry/Soldermask Top")
		(3 "B.Mask" user "Board Geometry/Soldermask Bottom")
		(17 "Dwgs.User" user "User.Drawings")
		(19 "Cmts.User" user "User.Comments")
		(21 "Eco1.User" user "User.Eco1")
		(23 "Eco2.User" user "User.Eco2")
		(25 "Edge.Cuts" user "Board Geometry/Outline")
		(27 "Margin" user)
		(31 "F.CrtYd" user "Package Geometry/Place Bound Top")
		(29 "B.CrtYd" user "Package Geometry/Place Bound Bottom")
		(35 "F.Fab" user "Ref Des/Assembly Top")
		(33 "B.Fab" user "Ref Des/Assembly Bottom")
	)
	(footprint ""
		(layer "F.Cu")
		(at 53.721 -132.461 -90)
		(property "Reference" "R320"
			(at 0 0 270)
			(layer "F.SilkS")
			(hide yes)
			(effects
				(font
					(size 1.27 1.27)
				)
			)
		)
		(property "Value" "0R2J-2-GP"
			(at 0.064008 -3.993896 270)
			(unlocked yes)
			(layer "F.Fab")
			(hide yes)
			(effects
				(font
					(size 1.016 1.016)
					(thickness 0.1524)
				)
			)
		)
		(property "Device Type" "R402H16"
			(at 0.064008 -5.517896 270)
			(unlocked yes)
			(layer "F.Fab")
			(hide yes)
			(effects
				(font
					(size 1.016 1.016)
					(thickness 0.1524)
				)
			)
		)
		(duplicate_pad_numbers_are_jumpers no)
		(fp_line
			(start -0.508 -0.9398)
			(end -0.508 0.9398)
			(stroke
				(width 0.1524)
				(type default)
			)
			(layer "F.SilkS")
		)
		(fp_line
			(start 0.508 -0.9398)
			(end -0.508 -0.9398)
			(stroke
				(width 0.1524)
				(type default)
			)
			(layer "F.SilkS")
		)
		(fp_rect
			(start -0.508 0.9398)
			(end 0.508 -0.9398)
			(stroke
				(width 0)
				(type default)
			)
			(fill no)
			(layer "F.CrtYd")
		)
		(fp_rect
			(start -0.508 0.9398)
			(end 0.508 -0.9398)
			(stroke
				(width 0)
				(type default)
			)
			(fill no)
			(layer "F.Fab")
		)
		(pad "1" smd custom
			(at 0 -0.4445 270)
			(size 0.1397 0.1397)
			(layers "F.Cu" "F.Mask" "F.Paste")
			(net "ADC_P1V53V")
			(options
				(clearance outline)
				(anchor circle)
			)
			(primitives
				(gr_poly
					(pts
						(arc
							(start -0.1778 -0.2794)
							(mid -0.249642 -0.249642)
							(end -0.2794 -0.1778)
						)
						(arc
							(start -0.2794 0.1778)
							(mid -0.249642 0.249642)
							(end -0.1778 0.2794)
						)
						(arc
							(start 0.1778 0.2794)
							(mid 0.249642 0.249642)
							(end 0.2794 0.1778)
						)
						(arc
							(start 0.2794 -0.1778)
							(mid 0.249642 -0.249642)
							(end 0.1778 -0.2794)
						)
					)
					(width 0)
					(fill yes)
				)
			)
		)
		(pad "2" smd custom
			(at 0 0.4445 270)
			(size 0.1397 0.1397)
			(layers "F.Cu" "F.Mask" "F.Paste")
			(net "ADC_P1V53_BMC")
			(options
				(clearance outline)
				(anchor circle)
			)
			(primitives
				(gr_poly
					(pts
						(arc
							(start -0.1778 -0.2794)
							(mid -0.249642 -0.249642)
							(end -0.2794 -0.1778)
						)
						(arc
							(start -0.2794 0.1778)
							(mid -0.249642 0.249642)
							(end -0.1778 0.2794)
						)
						(arc
							(start 0.1778 0.2794)
							(mid 0.249642 0.249642)
							(end 0.2794 0.1778)
						)
						(arc
							(start 0.2794 -0.1778)
							(mid 0.249642 -0.249642)
							(end 0.1778 -0.2794)
						)
					)
					(width 0)
					(fill yes)
				)
			)
		)
	)
	(footprint ""
		(layer "F.Cu")
		(at 52.671726 -37.968936)
		(property "Reference" "R618"
			(at 0 0 0)
			(layer "F.SilkS")
			(hide yes)
			(effects
				(font
					(size 1.27 1.27)
				)
			)
		)
		(property "Value" "47KR2F-GP"
			(at 0.064008 -3.993896 0)
			(unlocked yes)
			(layer "F.Fab")
			(hide yes)
			(effects
				(font
					(size 1.016 1.016)
					(thickness 0.1524)
				)
			)
		)
		(property "Device Type" "R402H16"
			(at 0.064008 -5.517896 0)
			(unlocked yes)
			(layer "F.Fab")
			(hide yes)
			(effects
				(font
					(size 1.016 1.016)
					(thickness 0.1524)
				)
			)
		)
		(duplicate_pad_numbers_are_jumpers no)
		(fp_line
			(start -0.508 -0.9398)
			(end -0.508 0.9398)
			(stroke
				(width 0.1524)
				(type default)
			)
			(layer "F.SilkS")
		)
		(fp_line
			(start 0.508 -0.9398)
			(end -0.508 -0.9398)
			(stroke
				(width 0.1524)
				(type default)
			)
			(layer "F.SilkS")
		)
		(fp_rect
			(start -0.508 0.9398)
			(end 0.508 -0.9398)
			(stroke
				(width 0)
				(type default)
			)
			(fill no)
			(layer "F.CrtYd")
		)
		(fp_rect
			(start -0.508 0.9398)
			(end 0.508 -0.9398)
			(stroke
				(width 0)
				(type default)
			)
			(fill no)
			(layer "F.Fab")
		)
		(pad "1" smd custom
			(at 0 -0.4445)
			(size 0.1397 0.1397)
			(layers "F.Cu" "F.Mask" "F.Paste")
			(net "P12V_PCIE")
			(options
				(clearance outline)
				(anchor circle)
			)
			(primitives
				(gr_poly
					(pts
						(arc
							(start -0.1778 -0.2794)
							(mid -0.249642 -0.249642)
							(end -0.2794 -0.1778)
						)
						(arc
							(start -0.2794 0.1778)
							(mid -0.249642 0.249642)
							(end -0.1778 0.2794)
						)
						(arc
							(start 0.1778 0.2794)
							(mid 0.249642 0.249642)
							(end 0.2794 0.1778)
						)
						(arc
							(start 0.2794 -0.1778)
							(mid 0.249642 -0.249642)
							(end 0.1778 -0.2794)
						)
					)
					(width 0)
					(fill yes)
				)
			)
		)
		(pad "2" smd custom
			(at 0 0.4445)
			(size 0.1397 0.1397)
			(layers "F.Cu" "F.Mask" "F.Paste")
			(net "Q42_D")
			(options
				(clearance outline)
				(anchor circle)
			)
			(primitives
				(gr_poly
					(pts
						(arc
							(start -0.1778 -0.2794)
							(mid -0.249642 -0.249642)
							(end -0.2794 -0.1778)
						)
						(arc
							(start -0.2794 0.1778)
							(mid -0.249642 0.249642)
							(end -0.1778 0.2794)
						)
						(arc
							(start 0.1778 0.2794)
							(mid 0.249642 0.249642)
							(end 0.2794 0.1778)
						)
						(arc
							(start 0.2794 -0.1778)
							(mid 0.249642 -0.249642)
							(end 0.1778 -0.2794)
						)
					)
					(width 0)
					(fill yes)
				)
			)
		)
	)
	(footprint ""
		(layer "F.Cu")
		(at 181.61 -29.845 -90)
		(property "Reference" "C403"
			(at 0 0 270)
			(layer "F.SilkS")
			(hide yes)
			(effects
				(font
					(size 1.27 1.27)
				)
			)
		)
		(property "Value" "SCD22U10V2KX-1GP"
			(at 1.1811 -2.7051 270)
			(unlocked yes)
			(layer "F.Fab")
			(hide yes)
			(effects
				(font
					(size 1.016 1.016)
					(thickness 0.1524)
				)
			)
		)
		(property "Device Type" "C402H22"
			(at 1.1811 -4.2291 270)
			(unlocked yes)
			(layer "F.Fab")
			(hide yes)
			(effects
				(font
					(size 1.016 1.016)
					(thickness 0.1524)
				)
			)
		)
		(duplicate_pad_numbers_are_jumpers no)
		(fp_rect
			(start -0.4318 0.9525)
			(end 0.4318 -0.9525)
			(stroke
				(width 0)
				(type default)
			)
			(fill no)
			(layer "F.CrtYd")
		)
		(fp_rect
			(start -0.4318 0.9525)
			(end 0.4318 -0.9525)
			(stroke
				(width 0)
				(type default)
			)
			(fill no)
			(layer "F.Fab")
		)
		(pad "1" smd custom
			(at 0 -0.4445 270)
			(size 0.1524 0.1524)
			(layers "F.Cu" "F.Mask" "F.Paste")
			(net "PCIE_TX_CAP_P91")
			(options
				(clearance outline)
				(anchor circle)
			)
			(primitives
				(gr_poly
					(pts
						(arc
							(start 0.3048 -0.2032)
							(mid 0.275042 -0.275042)
							(end 0.2032 -0.3048)
						)
						(arc
							(start -0.2032 -0.3048)
							(mid -0.275042 -0.275042)
							(end -0.3048 -0.2032)
						)
						(arc
							(start -0.3048 0.2032)
							(mid -0.275042 0.275042)
							(end -0.2032 0.3048)
						)
						(arc
							(start 0.2032 0.3048)
							(mid 0.275042 0.275042)
							(end 0.3048 0.2032)
						)
					)
					(width 0)
					(fill yes)
				)
			)
		)
		(pad "2" smd custom
			(at 0 0.4445 270)
			(size 0.1524 0.1524)
			(layers "F.Cu" "F.Mask" "F.Paste")
			(net "PCIE_TX_P91")
			(options
				(clearance outline)
				(anchor circle)
			)
			(primitives
				(gr_poly
					(pts
						(arc
							(start 0.3048 -0.2032)
							(mid 0.275042 -0.275042)
							(end 0.2032 -0.3048)
						)
						(arc
							(start -0.2032 -0.3048)
							(mid -0.275042 -0.275042)
							(end -0.3048 -0.2032)
						)
						(arc
							(start -0.3048 0.2032)
							(mid -0.275042 0.275042)
							(end -0.2032 0.3048)
						)
						(arc
							(start 0.2032 0.3048)
							(mid 0.275042 0.275042)
							(end 0.3048 0.2032)
						)
					)
					(width 0)
					(fill yes)
				)
			)
		)
	)
	(footprint ""
		(layer "F.Cu")
		(at 157.877002 -54.256432 90)
		(property "Reference" "C268"
			(at 0 0 90)
			(layer "F.SilkS")
			(hide yes)
			(effects
				(font
					(size 1.27 1.27)
				)
			)
		)
		(property "Value" "SC100P50V2JN-3GP"
			(at 1.1811 -2.7051 90)
			(unlocked yes)
			(layer "F.Fab")
			(hide yes)
			(effects
				(font
					(size 1.016 1.016)
					(thickness 0.1524)
				)
			)
		)
		(property "Device Type" "C402H22"
			(at 1.1811 -4.2291 90)
			(unlocked yes)
			(layer "F.Fab")
			(hide yes)
			(effects
				(font
					(size 1.016 1.016)
					(thickness 0.1524)
				)
			)
		)
		(duplicate_pad_numbers_are_jumpers no)
		(fp_rect
			(start -0.4318 0.9525)
			(end 0.4318 -0.9525)
			(stroke
				(width 0)
				(type default)
			)
			(fill no)
			(layer "F.CrtYd")
		)
		(fp_rect
			(start -0.4318 0.9525)
			(end 0.4318 -0.9525)
			(stroke
				(width 0)
				(type default)
			)
			(fill no)
			(layer "F.Fab")
		)
		(pad "1" smd custom
			(at 0 -0.4445 90)
			(size 0.1524 0.1524)
			(layers "F.Cu" "F.Mask" "F.Paste")
			(net "P0V9_VFB")
			(options
				(clearance outline)
				(anchor circle)
			)
			(primitives
				(gr_poly
					(pts
						(arc
							(start 0.3048 -0.2032)
							(mid 0.275042 -0.275042)
							(end 0.2032 -0.3048)
						)
						(arc
							(start -0.2032 -0.3048)
							(mid -0.275042 -0.275042)
							(end -0.3048 -0.2032)
						)
						(arc
							(start -0.3048 0.2032)
							(mid -0.275042 0.275042)
							(end -0.2032 0.3048)
						)
						(arc
							(start 0.2032 0.3048)
							(mid 0.275042 0.275042)
							(end 0.3048 0.2032)
						)
					)
					(width 0)
					(fill yes)
				)
			)
		)
		(pad "2" smd custom
			(at 0 0.4445 90)
			(size 0.1524 0.1524)
			(layers "F.Cu" "F.Mask" "F.Paste")
			(net "P0V9_VFB_R")
			(options
				(clearance outline)
				(anchor circle)
			)
			(primitives
				(gr_poly
					(pts
						(arc
							(start 0.3048 -0.2032)
							(mid 0.275042 -0.275042)
							(end 0.2032 -0.3048)
						)
						(arc
							(start -0.2032 -0.3048)
							(mid -0.275042 -0.275042)
							(end -0.3048 -0.2032)
						)
						(arc
							(start -0.3048 0.2032)
							(mid -0.275042 0.275042)
							(end -0.2032 0.3048)
						)
						(arc
							(start 0.2032 0.3048)
							(mid 0.275042 0.275042)
							(end 0.3048 0.2032)
						)
					)
					(width 0)
					(fill yes)
				)
			)
		)
	)
	(footprint ""
		(layer "F.Cu")
		(at 44.3738 -184.8866 90)
		(property "Reference" "C689"
			(at 0 0 90)
			(layer "F.SilkS")
			(hide yes)
			(effects
				(font
					(size 1.27 1.27)
				)
			)
		)
		(property "Value" "SC220P50V3JN-GP"
			(at 0 -2.8194 90)
			(unlocked yes)
			(layer "F.Fab")
			(hide yes)
			(effects
				(font
					(size 1.016 1.016)
					(thickness 0.1524)
				)
			)
		)
		(property "Device Type" "C603H36"
			(at 0 -4.3434 90)
			(unlocked yes)
			(layer "F.Fab")
			(hide yes)
			(effects
				(font
					(size 1.016 1.016)
					(thickness 0.1524)
				)
			)
		)
		(duplicate_pad_numbers_are_jumpers no)
		(fp_line
			(start 0.508 0)
			(end -0.508 0)
			(stroke
				(width 0.2032)
				(type default)
			)
			(layer "F.SilkS")
		)
		(fp_rect
			(start -0.5842 1.3335)
			(end 0.5842 -1.3335)
			(stroke
				(width 0)
				(type default)
			)
			(fill no)
			(layer "F.CrtYd")
		)
		(fp_rect
			(start -0.5842 1.3335)
			(end 0.5842 -1.3335)
			(stroke
				(width 0)
				(type default)
			)
			(fill no)
			(layer "F.Fab")
		)
		(pad "1" smd custom
			(at 0 -0.762 90)
			(size 0.2159 0.2159)
			(layers "F.Cu" "F.Mask" "F.Paste")
			(net "BMC_I2C9_CLKBUF2_SCL_R")
			(options
				(clearance outline)
				(anchor circle)
			)
			(primitives
				(gr_poly
					(pts
						(arc
							(start -0.3302 -0.4318)
							(mid -0.402042 -0.402042)
							(end -0.4318 -0.3302)
						)
						(arc
							(start -0.4318 0.3302)
							(mid -0.402042 0.402042)
							(end -0.3302 0.4318)
						)
						(arc
							(start 0.3302 0.4318)
							(mid 0.402042 0.402042)
							(end 0.4318 0.3302)
						)
						(arc
							(start 0.4318 -0.3302)
							(mid 0.402042 -0.402042)
							(end 0.3302 -0.4318)
						)
					)
					(width 0)
					(fill yes)
				)
			)
		)
		(pad "2" smd custom
			(at 0 0.762 90)
			(size 0.2159 0.2159)
			(layers "F.Cu" "F.Mask" "F.Paste")
			(net "GND")
			(options
				(clearance outline)
				(anchor circle)
			)
			(primitives
				(gr_poly
					(pts
						(arc
							(start -0.3302 -0.4318)
							(mid -0.402042 -0.402042)
							(end -0.4318 -0.3302)
						)
						(arc
							(start -0.4318 0.3302)
							(mid -0.402042 0.402042)
							(end -0.3302 0.4318)
						)
						(arc
							(start 0.3302 0.4318)
							(mid 0.402042 0.402042)
							(end 0.4318 0.3302)
						)
						(arc
							(start 0.4318 -0.3302)
							(mid 0.402042 -0.402042)
							(end 0.3302 -0.4318)
						)
					)
					(width 0)
					(fill yes)
				)
			)
		)
	)
	(footprint ""
		(layer "F.Cu")
		(at 71.749412 -195.689474)
		(property "Reference" "R453"
			(at 0 0 0)
			(layer "F.SilkS")
			(hide yes)
			(effects
				(font
					(size 1.27 1.27)
				)
			)
		)
		(property "Value" "10KR2F-2-GP"
			(at 0.064008 -3.993896 0)
			(unlocked yes)
			(layer "F.Fab")
			(hide yes)
			(effects
				(font
					(size 1.016 1.016)
					(thickness 0.1524)
				)
			)
		)
		(property "Device Type" "R402H16"
			(at 0.064008 -5.517896 0)
			(unlocked yes)
			(layer "F.Fab")
			(hide yes)
			(effects
				(font
					(size 1.016 1.016)
					(thickness 0.1524)
				)
			)
		)
		(duplicate_pad_numbers_are_jumpers no)
		(fp_line
			(start -0.508 -0.9398)
			(end -0.508 0.9398)
			(stroke
				(width 0.1524)
				(type default)
			)
			(layer "F.SilkS")
		)
		(fp_line
			(start 0.508 -0.9398)
			(end -0.508 -0.9398)
			(stroke
				(width 0.1524)
				(type default)
			)
			(layer "F.SilkS")
		)
		(fp_rect
			(start -0.508 0.9398)
			(end 0.508 -0.9398)
			(stroke
				(width 0)
				(type default)
			)
			(fill no)
			(layer "F.CrtYd")
		)
		(fp_rect
			(start -0.508 0.9398)
			(end 0.508 -0.9398)
			(stroke
				(width 0)
				(type default)
			)
			(fill no)
			(layer "F.Fab")
		)
		(pad "1" smd custom
			(at 0 -0.4445)
			(size 0.1397 0.1397)
			(layers "F.Cu" "F.Mask" "F.Paste")
			(net "GND")
			(options
				(clearance outline)
				(anchor circle)
			)
			(primitives
				(gr_poly
					(pts
						(arc
							(start -0.1778 -0.2794)
							(mid -0.249642 -0.249642)
							(end -0.2794 -0.1778)
						)
						(arc
							(start -0.2794 0.1778)
							(mid -0.249642 0.249642)
							(end -0.1778 0.2794)
						)
						(arc
							(start 0.1778 0.2794)
							(mid 0.249642 0.249642)
							(end 0.2794 0.1778)
						)
						(arc
							(start 0.2794 -0.1778)
							(mid 0.249642 -0.249642)
							(end 0.1778 -0.2794)
						)
					)
					(width 0)
					(fill yes)
				)
			)
		)
		(pad "2" smd custom
			(at 0 0.4445)
			(size 0.1397 0.1397)
			(layers "F.Cu" "F.Mask" "F.Paste")
			(net "IOEXP1_AD0")
			(options
				(clearance outline)
				(anchor circle)
			)
			(primitives
				(gr_poly
					(pts
						(arc
							(start -0.1778 -0.2794)
							(mid -0.249642 -0.249642)
							(end -0.2794 -0.1778)
						)
						(arc
							(start -0.2794 0.1778)
							(mid -0.249642 0.249642)
							(end -0.1778 0.2794)
						)
						(arc
							(start 0.1778 0.2794)
							(mid 0.249642 0.249642)
							(end 0.2794 0.1778)
						)
						(arc
							(start 0.2794 -0.1778)
							(mid 0.249642 -0.249642)
							(end 0.1778 -0.2794)
						)
					)
					(width 0)
					(fill yes)
				)
			)
		)
	)
	(footprint ""
		(layer "F.Cu")
		(at 32.418782 -112.19307)
		(property "Reference" "TP308"
			(at 0 0 0)
			(layer "F.SilkS")
			(hide yes)
			(effects
				(font
					(size 1.27 1.27)
				)
			)
		)
		(property "Value" "TPAD28-2-GP"
			(at -0.0127 -1.6637 0)
			(unlocked yes)
			(layer "F.Fab")
			(hide yes)
			(effects
				(font
					(size 1.016 1.016)
					(thickness 0.1524)
				)
			)
		)
		(property "Device Type" "TPAD28"
			(at -0.0127 -3.1877 0)
			(unlocked yes)
			(layer "F.Fab")
			(hide yes)
			(effects
				(font
					(size 1.016 1.016)
					(thickness 0.1524)
				)
			)
		)
		(duplicate_pad_numbers_are_jumpers no)
		(fp_poly
			(pts
				(arc
					(start 0.3556 0)
					(mid -0.3556 0)
					(end 0.3556 0)
				)
			)
			(stroke
				(width 0)
				(type default)
			)
			(fill no)
			(layer "F.CrtYd")
		)
		(fp_poly
			(pts
				(arc
					(start 0.6096 0)
					(mid -0.6096 0)
					(end 0.6096 0)
				)
			)
			(stroke
				(width 0)
				(type default)
			)
			(fill no)
			(layer "F.Fab")
		)
		(pad "1" smd circle
			(at 0 0)
			(size 0.7112 0.7112)
			(layers "F.Cu" "F.Mask" "F.Paste")
			(net "TP_GPIOD7")
		)
	)
)
